FILE_TYPE = CONNECTIVITY;
{Allegro Design Entry HDL 16.6-p007 (v16-6-112F) 10/10/2012}
"PAGE_NUMBER" = 207;
0"NC";
1"PVCCIN_CPU1\g";
2"GND\g";
3"GND\g";
4"GND\g";
5"VR_FET_SW_P12V_STBY_PVCCIN_CPU1\g";
6"GND\g";
7"VR_FET_SW_P12V_STBY_PVCCIN_CPU1\g";
8"GND\g";
9"P5V_STBY\g";
10"P5V_STBY\g";
11"GND\g";
12"PVCCIN_CPU1\g";
13"GND\g";
14"GND\g";
15"GND\g";
16"GND\g";
17"GND\g";
18"GND\g";
19"GND\g";
20"UN$207$3D01R5F-GP$I76$2";
21"UN$207$3D01R5F-GP$I85$2";
22"VR_PVCCIN_CPU1_AIREF2";
23"ISENSE_PVCCIN_CPU1_PH2_IMON";
24"VR_PVCCIN_CPU1_PHASE2"VOLTAGE"5";
25"VR_PVCCIN_CPU1_PH2_VCIN"VOLTAGE"5";
26"A_TSENSE_PVCCIN_CPU1";
27"VR_PVCCIN_CPU1_PWM2";
28"VR_PVCCIN_CPU1_PH2_BOOT";
29"VR_PVCCIN_CPU1_PH2_PHASE"VOLTAGE"5";
30"VR_PVCCIN_CPU1_PH2_BOOT_R";
31"VR_PVCCIN_CPU1_PH1_PHASE"VOLTAGE"5";
32"VR_PVCCIN_CPU1_PH1_BOOT";
33"VR_PVCCIN_CPU1_PWM1";
34"VR_PVCCIN_CPU1_PH1_OCSET";
35"NC_PVCCIN_CPU1_PH1_P31";
36"A_TSENSE_PVCCIN_CPU1";
37"VR_PVCCIN_CPU1_PHASE1"VOLTAGE"5";
38"VR_PVCCIN_CPU1_PH1_BOOT_R";
39"VR_PVCCIN_CPU1_AIREF1";
40"TP_PVCCINC_CPU1_PH1_GL_1";
41"TP_PVCCINC_CPU1_PH1_GL_0";
42"TP_PVCCINC_CPU1_PH2_GL_0";
43"VR_PVCCIN_CPU1_PH1_VCIN"VOLTAGE"5";
44"ISENSE_PVCCIN_CPU1_PH1_IMON";
45"VR_PVCCIN_CPU1_PH2_OCSET";
46"NC_PVCCIN_CPU1_PH2_P31";
47"TP_PVCCINC_CPU1_PH2_GL_1";
48"GND\g";
%"INDUCTOR"
"1","(-2000,3525)","0","mstr_discrete","I10";
;
CDS_LIB"mstr_discrete"
CDS_SEC"1"
$SEC"1"
CDS_LOCATION"L1E1"
ROOM"PVCCIN_CPU1_PWR_VR"
PACK_TYPE"SM"
LOCATION"L1E1"
VALUE"0.12UH"
PART_NUMBER"D92183-034"
MATERIAL"IND";
"INA\NAC"
$PN"1"37;
"INB\NAC"
$PN"2"12;
%"PVCCIN_CPU1"
"1","(-1075,1025)","0","mstr_symbols","I14";
;
HDL_POWER"PVCCIN_CPU1"
BODY_TYPE"PLUMBING"
CDS_LIB"mstr_symbols"
VOLTAGE"2.0V";
"G\NAC"1;
%"INDUCTOR"
"1","(-2100,925)","0","mstr_discrete","I16";
;
CDS_SEC"1"
$SEC"1"
ROOM"PVCCIN_CPU1_PWR_VR"
CDS_LIB"mstr_discrete"
CDS_LOCATION"L1D3"
PART_NUMBER"D92183-034"
MATERIAL"IND"
PACK_TYPE"SM"
LOCATION"L1D3"
VALUE"0.12UH";
"INA\NAC"
$PN"1"24;
"INB\NAC"
$PN"2"1;
%"GND"
"1","(-1075,450)","0","mstr_symbols","I17";
;
HDL_POWER"GND"
BODY_TYPE"PLUMBING"
VOLTAGE"0"
CDS_LIB"mstr_symbols"
SIZE"1B"
BOM_COST"PROC_VRD_VCCIN_CPU0"
ROOM"PVCCIN_CPU1_PWR_VR";
"A\NAC"2;
%"CAP_A"
"1","(-1525,775)","0","dev_discrete","I18";
;
ROOM"PVCCIN_CPU1_PWR_VR"
SEC"1"
SEC_TYPE"0603V"
CDS_SEC"1"
BOM_COST"PROC_VRD_VCCIN_CPU0"
CDS_LOCATION"C1E3"
CDS_LIB"dev_discrete"
LOCATION"C1E3"
VALUE"22.0UF"
PART_NUMBER"E15431-004"
PACK_TYPE"0603V"
MATERIAL"X6S"
TOLERANCE"20%"
VOLTAGE"4V";
"B"
$PN"2"2;
"A"
$PN"1"1;
%"GND"
"1","(-2725,3075)","0","mstr_symbols","I19";
;
HDL_POWER"GND"
BODY_TYPE"PLUMBING"
CDS_LIB"mstr_symbols"
VOLTAGE"0"
SIZE"1B"
BOM_COST"PROC_VRD_VCCIN_CPU0"
ROOM"PVCCIN_CPU1_PWR_VR";
"A\NAC"3;
%"IR354XX"
"1","(-3450,3825)","0","mstr_discrete","I20";
;
CDS_SEC"1"
SEC_TYPE"SM"
SEC"1"
CDS_LOCATION"EU1E2"
PACK_TYPE"SM"
CDS_LIB"mstr_discrete"
ROOM"PVCCIN_CPU1_PWR_VR"
PART_NUMBER"H73688-001"
VALUE"IR35411"
LOCATION"EU1E2"
MATERIAL"IC";
"TOUT_FLT"
$PN"36"36;
"NC"
$PN"31"35;
"OCSET"
$PN"37"34;
"IOUT"
$PN"38"44;
"SW"
$PN"10"37;
"BOOST"
$PN"33"38;
"REFIN"
$PN"39"39;
"PWM"
$PN"34"33;
"PHASE"
$PN"32"31;
"VIN<0>"
$PN"25"5;
"VCC"
$PN"3"43;
"VIN<1>"
$PN"30"5;
"EN"
$PN"35"9;
"VDRV"
$PN"4"9;
"VOS"
$PN"1"12;
"LGND"
$PN"2"3;
"PGND<1>"
$PN"7"3;
"PGND<2>"
$PN"40"3;
"PGND<0>"
$PN"5"3;
"GL<0>"
$PN"6"41;
"GL<1>"
$PN"41"40;
%"GND"
"1","(-2775,550)","0","mstr_symbols","I23";
;
HDL_POWER"GND"
BODY_TYPE"PLUMBING"
CDS_LIB"mstr_symbols"
VOLTAGE"0"
SIZE"1B"
BOM_COST"PROC_VRD_VCCIN_CPU0"
ROOM"PVCCIN_CPU1_PWR_VR";
"A\NAC"4;
%"IR354XX"
"1","(-3475,1225)","0","mstr_discrete","I24";
;
CDS_SEC"1"
PACK_TYPE"SM"
SEC_TYPE"SM"
SEC"1"
CDS_LIB"mstr_discrete"
CDS_LOCATION"EU1D4"
ROOM"PVCCIN_CPU1_PWR_VR"
VALUE"IR35411"
LOCATION"EU1D4"
MATERIAL"IC"
PART_NUMBER"H73688-001";
"TOUT_FLT"
$PN"36"26;
"NC"
$PN"31"46;
"OCSET"
$PN"37"45;
"IOUT"
$PN"38"23;
"SW"
$PN"10"24;
"BOOST"
$PN"33"30;
"REFIN"
$PN"39"22;
"PWM"
$PN"34"27;
"PHASE"
$PN"32"29;
"VIN<0>"
$PN"25"7;
"VCC"
$PN"3"25;
"VIN<1>"
$PN"30"7;
"EN"
$PN"35"10;
"VDRV"
$PN"4"10;
"VOS"
$PN"1"1;
"LGND"
$PN"2"4;
"PGND<1>"
$PN"7"4;
"PGND<2>"
$PN"40"4;
"PGND<0>"
$PN"5"4;
"GL<0>"
$PN"6"42;
"GL<1>"
$PN"41"47;
%"RES"
"1","(-5700,4625)","0","mstr_discrete","I26";
;
CDS_SEC"1"
SEC_TYPE"0402"
ROOM"PVCCIN_CPU1_PWR_VR"
CDS_LOCATION"R9R2"
SEC"1"
CDS_LIB"mstr_discrete"
MATERIAL"CHIP"
PART_NUMBER"G21796-090"
PACK_TYPE"0402"
LOCATION"R9R2"
WATTAGE"1/16W"
TOLERANCE"1%"
VALUE"1.0";
"B"
$PN"2"9;
"A"
$PN"1"43;
%"VCC_CORE"
"1","(-7525,4475)","0","mstr_symbols","I27";
;
CDS_LIB"mstr_symbols"
HDL_POWER"VR_FET_SW_P12V_STBY_PVCCIN_CPU1";
"A"5;
%"CAP"
"1","(-5250,4100)","0","mstr_discrete","I28";
;
CDS_SEC"1"
SEC_TYPE"0402"
SEC"1"
CDS_LOCATION"C1E7"
ROOM"PVCCIN_CPU1_PWR_VR"
CDS_LIB"mstr_discrete"
LOCATION"C1E7"
VALUE"0.22UF"
VOLTAGE"16V"
PART_NUMBER"A36096-155"
TOLERANCE"10%"
PACK_TYPE"0402"
MATERIAL"X7R";
"A"
$PN"1"9;
"B"
$PN"2"6;
%"CAP_A"
"1","(-5375,4100)","2","dev_discrete","I29";
;
CDS_LIB"dev_discrete"
ROOM"PVCCIN_CPU1_PWR_VR"
SEC_TYPE"0402V"
CDS_SEC"1"
CDS_LOCATION"C1E6"
SEC"1"
PART_NUMBER"D97712-004"
PACK_TYPE"0402V"
LOCATION"C1E6"
VALUE"1.0UF"
VOLTAGE"6.3V"
TOLERANCE"10%"
MATERIAL"X6S";
"B"
$PN"2"6;
"A"
$PN"1"9;
%"CAP"
"1","(-6000,3475)","2","mstr_discrete","I30";
;
CDS_SEC"1"
SEC"1"
SPOF"TRUE"
SEC_TYPE"0402"
ROOM"PVCCIN_CPU1_PWR_VR"
NO_XNET_CONNECTION"1"
CDS_LOCATION"C1E11"
CDS_LIB"mstr_discrete"
TOLERANCE"10%"
PART_NUMBER"A36096-104"
PACK_TYPE"0402"
MATERIAL"X7R"
VOLTAGE"16V"
LOCATION"C1E11"
VALUE"0.220UF";
"A"
$PN"1"32;
"B"
$PN"2"31;
%"CAP"
"1","(-5950,4075)","0","mstr_discrete","I32";
;
CDS_SEC"1"
SEC"1"
SEC_TYPE"0402"
CDS_LOCATION"C1E8"
ROOM"PVCCIN_CPU1_PWR_VR"
CDS_LIB"mstr_discrete"
TOLERANCE"10%"
LOCATION"C1E8"
VALUE"1.0UF"
VOLTAGE"16V"
PART_NUMBER"D97712-011"
PACK_TYPE"0402"
MATERIAL"X6S";
"A"
$PN"1"43;
"B"
$PN"2"6;
%"CAP_A"
"1","(-6250,4100)","0","dev_discrete","I33";
;
SEC"1"
SEC_TYPE"0402V"
CDS_SEC"1"
ROOM"PVCCIN_CPU1_PWR_VR"
CDS_LOCATION"C1E14"
CDS_LIB"dev_discrete"
PACK_TYPE"0402V"
VOLTAGE"16V"
LOCATION"C1E14"
VALUE"0.1UF"
PART_NUMBER"A36096-030"
TOLERANCE"10%"
MATERIAL"X7R";
"B"
$PN"2"6;
"A"
$PN"1"5;
%"CAP"
"1","(-6575,4100)","0","mstr_discrete","I34";
;
CDS_SEC"1"
SEC_TYPE"0402"
SEC"1"
CDS_LOCATION"C1E13"
ROOM"PVCCIN_CPU1_PWR_VR"
CDS_LIB"mstr_discrete"
PACK_TYPE"0402"
PART_NUMBER"D97712-011"
TOLERANCE"10%"
VOLTAGE"16V"
LOCATION"C1E13"
VALUE"1.0UF"
MATERIAL"X6S";
"A"
$PN"1"5;
"B"
$PN"2"6;
%"CAP"
"1","(-5075,1550)","0","mstr_discrete","I36";
;
CDS_SEC"1"
CDS_LOCATION"C1E25"
SEC_TYPE"0402"
SEC"1"
CDS_LIB"mstr_discrete"
ROOM"PVCCIN_CPU1_PWR_VR"
VOLTAGE"16V"
VALUE"0.22UF"
LOCATION"C1E25"
TOLERANCE"10%"
PACK_TYPE"0402"
MATERIAL"X7R"
PART_NUMBER"A36096-155";
"A"
$PN"1"10;
"B"
$PN"2"8;
%"CAP_A"
"1","(-5250,1550)","2","dev_discrete","I37";
;
CDS_LOCATION"C1E23"
SEC_TYPE"0402V"
ROOM"PVCCIN_CPU1_PWR_VR"
SEC"1"
CDS_SEC"1"
CDS_LIB"dev_discrete"
TOLERANCE"10%"
MATERIAL"X6S"
PART_NUMBER"D97712-004"
LOCATION"C1E23"
VALUE"1.0UF"
VOLTAGE"6.3V"
PACK_TYPE"0402V";
"B"
$PN"2"8;
"A"
$PN"1"10;
%"CAP"
"1","(-5875,850)","2","mstr_discrete","I38";
;
CDS_SEC"1"
CDS_LOCATION"C1D36"
CDS_LIB"mstr_discrete"
ROOM"PVCCIN_CPU1_PWR_VR"
NO_XNET_CONNECTION"1"
SEC"1"
SPOF"TRUE"
SEC_TYPE"0402"
PACK_TYPE"0402"
TOLERANCE"10%"
VOLTAGE"16V"
VALUE"0.220UF"
PART_NUMBER"A36096-104"
MATERIAL"X7R"
LOCATION"C1D36";
"A"
$PN"1"28;
"B"
$PN"2"29;
%"RES"
"1","(-5625,2000)","0","mstr_discrete","I39";
;
CDS_SEC"1"
CDS_LOCATION"R9R11"
SEC_TYPE"0402"
SEC"1"
ROOM"PVCCIN_CPU1_PWR_VR"
CDS_LIB"mstr_discrete"
LOCATION"R9R11"
PACK_TYPE"0402"
MATERIAL"CHIP"
PART_NUMBER"G21796-090"
TOLERANCE"1%"
WATTAGE"1/16W"
VALUE"1.0";
"B"
$PN"2"10;
"A"
$PN"1"25;
%"CAP"
"1","(-5850,1500)","0","mstr_discrete","I40";
;
CDS_SEC"1"
CDS_LOCATION"C1E24"
SEC"1"
SEC_TYPE"0402"
ROOM"PVCCIN_CPU1_PWR_VR"
CDS_LIB"mstr_discrete"
VOLTAGE"16V"
PACK_TYPE"0402"
PART_NUMBER"D97712-011"
VALUE"1.0UF"
LOCATION"C1E24"
TOLERANCE"10%"
MATERIAL"X6S";
"A"
$PN"1"25;
"B"
$PN"2"8;
%"CAP_A"
"1","(-6175,1500)","0","dev_discrete","I41";
;
CDS_LOCATION"C1D34"
SEC_TYPE"0402V"
SEC"1"
CDS_SEC"1"
ROOM"PVCCIN_CPU1_PWR_VR"
CDS_LIB"dev_discrete"
PACK_TYPE"0402V"
MATERIAL"X7R"
PART_NUMBER"A36096-030"
VALUE"0.1UF"
LOCATION"C1D34"
VOLTAGE"16V"
TOLERANCE"10%";
"B"
$PN"2"8;
"A"
$PN"1"7;
%"CAP"
"1","(-6450,1525)","0","mstr_discrete","I42";
;
CDS_SEC"1"
CDS_LOCATION"C1D35"
ROOM"PVCCIN_CPU1_PWR_VR"
SEC"1"
SEC_TYPE"0402"
CDS_LIB"mstr_discrete"
TOLERANCE"10%"
PART_NUMBER"D97712-011"
VALUE"1.0UF"
LOCATION"C1D35"
VOLTAGE"16V"
MATERIAL"X6S"
PACK_TYPE"0402";
"A"
$PN"1"7;
"B"
$PN"2"8;
%"CAP"
"1","(-6875,4100)","0","mstr_discrete","I43";
;
CDS_SEC"1"
SEC_TYPE"0805"
SEC"1"
ROOM"PVCCIN_CPU1_PWR_VR"
CDS_LOCATION"C9R7"
CDS_LIB"mstr_discrete"
VALUE"10UF"
LOCATION"C9R7"
VOLTAGE"16V"
PART_NUMBER"C95333-007"
TOLERANCE"10%"
PACK_TYPE"0805"
MATERIAL"X6S";
"A"
$PN"1"5;
"B"
$PN"2"6;
%"CAP"
"1","(-7175,4100)","0","mstr_discrete","I44";
;
CDS_SEC"1"
SEC_TYPE"0805"
SEC"1"
CDS_LOCATION"C9R10"
ROOM"PVCCIN_CPU1_PWR_VR"
CDS_LIB"mstr_discrete"
LOCATION"C9R10"
VALUE"10UF"
VOLTAGE"16V"
PART_NUMBER"C95333-007"
TOLERANCE"10%"
PACK_TYPE"0805"
MATERIAL"X6S";
"A"
$PN"1"5;
"B"
$PN"2"6;
%"CAP"
"1","(-7425,4100)","0","mstr_discrete","I48";
;
CDS_SEC"1"
SEC_TYPE"0805"
SEC"1"
CDS_LOCATION"C9R11"
ROOM"PVCCIN_CPU1_PWR_VR"
CDS_LIB"mstr_discrete"
LOCATION"C9R11"
VALUE"10UF"
VOLTAGE"16V"
PART_NUMBER"C95333-007"
TOLERANCE"10%"
PACK_TYPE"0805"
MATERIAL"X6S";
"A"
$PN"1"5;
"B"
$PN"2"6;
%"GND"
"1","(-7525,3750)","0","mstr_symbols","I49";
;
HDL_POWER"GND"
BODY_TYPE"PLUMBING"
VOLTAGE"0"
CDS_LIB"mstr_symbols"
SIZE"1B"
BOM_COST"PROC_VRD_VCCIN_CPU0"
ROOM"PVCCIN_CPU1_PWR_VR";
"A\NAC"6;
%"CAP"
"1","(-6800,1525)","0","mstr_discrete","I50";
;
CDS_SEC"1"
SEC_TYPE"0805"
SEC"1"
CDS_LOCATION"C9P22"
ROOM"PVCCIN_CPU1_PWR_VR"
CDS_LIB"mstr_discrete"
LOCATION"C9P22"
VALUE"10UF"
PACK_TYPE"0805"
VOLTAGE"16V"
MATERIAL"X6S"
TOLERANCE"10%"
PART_NUMBER"C95333-007";
"A"
$PN"1"7;
"B"
$PN"2"8;
%"CAP"
"1","(-7125,1525)","0","mstr_discrete","I51";
;
CDS_SEC"1"
CDS_LOCATION"C9P25"
SEC_TYPE"0805"
SEC"1"
ROOM"PVCCIN_CPU1_PWR_VR"
CDS_LIB"mstr_discrete"
VALUE"10UF"
LOCATION"C9P25"
VOLTAGE"16V"
PART_NUMBER"C95333-007"
TOLERANCE"10%"
PACK_TYPE"0805"
MATERIAL"X6S";
"A"
$PN"1"7;
"B"
$PN"2"8;
%"VCC_CORE"
"1","(-7500,1825)","0","mstr_symbols","I53";
;
CDS_LIB"mstr_symbols"
HDL_POWER"VR_FET_SW_P12V_STBY_PVCCIN_CPU1";
"A"7;
%"CAP"
"1","(-7450,1525)","0","mstr_discrete","I54";
;
CDS_SEC"1"
CDS_LOCATION"C9P26"
ROOM"PVCCIN_CPU1_PWR_VR"
SEC"1"
SEC_TYPE"0805"
CDS_LIB"mstr_discrete"
PART_NUMBER"C95333-007"
LOCATION"C9P26"
VALUE"10UF"
VOLTAGE"16V"
TOLERANCE"10%"
PACK_TYPE"0805"
MATERIAL"X6S";
"A"
$PN"1"7;
"B"
$PN"2"8;
%"GND"
"1","(-7500,1175)","0","mstr_symbols","I55";
;
HDL_POWER"GND"
BODY_TYPE"PLUMBING"
CDS_LIB"mstr_symbols"
VOLTAGE"0"
SIZE"1B"
BOM_COST"PROC_VRD_VCCIN_CPU0"
ROOM"PVCCIN_CPU1_PWR_VR";
"A\NAC"8;
%"P5V_STBY"
"1","(-4550,4775)","0","mstr_symbols","I56";
;
HDL_POWER"P5V_STBY"
BODY_TYPE"PLUMBING"
CDS_LIB"mstr_symbols"
SIZE"1B"
VOLTAGE"5.0V";
"G\NAC"9;
%"P5V_STBY"
"1","(-5150,2175)","0","mstr_symbols","I57";
;
HDL_POWER"P5V_STBY"
BODY_TYPE"PLUMBING"
SIZE"1B"
VOLTAGE"5.0V"
CDS_LIB"mstr_symbols";
"G\NAC"10;
%"CAP_A"
"1","(-975,3350)","0","dev_discrete","I58";
;
SEC_TYPE"0603V"
CDS_SEC"1"
SEC"1"
CDS_LOCATION"C1E9"
CDS_LIB"dev_discrete"
VOLTAGE"4V"
LOCATION"C1E9"
MATERIAL"X6S"
TOLERANCE"20%"
VALUE"22.0UF"
PART_NUMBER"E15431-004"
PACK_TYPE"0603V";
"B"
$PN"2"19;
"A"
$PN"1"12;
%"CAP_A"
"1","(-1075,775)","0","dev_discrete","I59";
;
CDS_SEC"1"
SEC_TYPE"0603V"
SEC"1"
CDS_LOCATION"C9P3"
CDS_LIB"dev_discrete"
LOCATION"C9P3"
PART_NUMBER"E15431-004"
PACK_TYPE"0603V"
TOLERANCE"20%"
MATERIAL"X6S"
VOLTAGE"4V"
VALUE"22.0UF";
"B"
$PN"2"2;
"A"
$PN"1"1;
%"RES"
"2","(-1025,1400)","0","mstr_discrete","I67";
;
CDS_LOCATION"R1E13"
CDS_SEC"1"
$SEC"1"
CDS_LIB"mstr_discrete"
LOCATION"R1E13"
PART_NUMBER"G21796-187"
MATERIAL"EMPTY"
VALUE"68.1K"
WATTAGE"1/16W"
TOLERANCE"1%"
PACK_TYPE"0402";
"A"
$PN"1"45;
"B"
$PN"2"13;
%"RES"
"2","(-550,4025)","0","mstr_discrete","I68";
;
CDS_LOCATION"R1E14"
CDS_SEC"1"
$SEC"1"
CDS_LIB"mstr_discrete"
LOCATION"R1E14"
VALUE"68.1K"
PART_NUMBER"G21796-187"
MATERIAL"EMPTY"
WATTAGE"1/16W"
TOLERANCE"1%"
PACK_TYPE"0402";
"A"
$PN"1"34;
"B"
$PN"2"11;
%"GND"
"1","(-550,3825)","0","mstr_symbols","I69";
;
HDL_POWER"GND"
BODY_TYPE"PLUMBING"
SIZE"1B"
VOLTAGE"0"
CDS_LIB"mstr_symbols"
BOM_COST"PROC_VRD_VCCIN_CPU0"
ROOM"PVCCIN_CPU1_PWR_VR";
"A\NAC"11;
%"PVCCIN_CPU1"
"1","(-975,3625)","0","mstr_symbols","I7";
;
HDL_POWER"PVCCIN_CPU1"
BODY_TYPE"PLUMBING"
CDS_LIB"mstr_symbols"
VOLTAGE"2.0V";
"G\NAC"12;
%"GND"
"1","(-1025,1175)","0","mstr_symbols","I70";
;
HDL_POWER"GND"
BODY_TYPE"PLUMBING"
SIZE"1B"
VOLTAGE"0"
CDS_LIB"mstr_symbols"
BOM_COST"PROC_VRD_VCCIN_CPU0"
ROOM"PVCCIN_CPU1_PWR_VR";
"A\NAC"13;
%"CAP_A"
"1","(-4175,3325)","0","dev_discrete","I71";
;
CDS_SEC"1"
$SEC"1"
CDS_LOCATION"CT24"
CDS_LIB"dev_discrete"
ROOM"PVCCIN_CPU0_PWR_VR"
STATUS"NOPOP"
PART_NUMBER"A36096-030"
PACK_TYPE"0402V"
MATERIAL"X7R"
TOLERANCE"10%"
VOLTAGE"16V"
VALUE"0.1UF"
LOCATION"CT24";
"B"
$PN"2"14;
"A"
$PN"1"39;
%"GND"
"1","(-4175,3000)","0","mstr_symbols","I72";
;
HDL_POWER"GND"
BODY_TYPE"PLUMBING"
CDS_LIB"mstr_symbols"
VOLTAGE"0"
SIZE"1B"
BOM_COST"PROC_VRD_VCCIN_CPU0"
ROOM"PVCCIN_CPU0_PWR_VR";
"A\NAC"14;
%"CAP"
"1","(-2450,3825)","0","mstr_discrete","I74";
;
CDS_SEC"1"
$SEC"1"
CDS_LOCATION"CT22"
CDS_LIB"mstr_discrete"
ROOM"VDDQ_KLM_PWR_VR"
STATUS"NOPOP"
LOCATION"CT22"
VOLTAGE"50V"
PART_NUMBER"A36096-046"
PACK_TYPE"0402LF"
MATERIAL"X7R"
VALUE"1000PF"
TOLERANCE"10%";
"A"
$PN"1"36;
"B"
$PN"2"15;
%"GND"
"1","(-2450,3625)","0","mstr_symbols","I75";
;
HDL_POWER"GND"
BODY_TYPE"PLUMBING"
CDS_LIB"mstr_symbols"
SIZE"1B"
VOLTAGE"0"
ROOM"VDDQ_KLM_PWR_VR";
"A\NAC"15;
%"3D01R5F-GP"
"1","(-2400,3075)","4","w_hdl","I76";
;
CDS_SEC"1"
$SEC"1"
CDS_LOCATION"RT16"
PACK_TYPE"SMD-RG5"
PART_NUMBER"64.3R015.16L"
CDS_LIB"w_hdl"
CDS_LMAN_SYM_OUTLINE"-50,75,50,-75"
STATUS"NOPOP"
LOCATION"RT16"
VALUE"3D01R5F-GP";
"2"
$PN"2"20;
"1"
$PN"1"16;
%"SC2K2P50V3KX-GP"
"1","(-2400,3375)","0","w_hdl","I77";
;
CDS_SEC"1"
$SEC"1"
CDS_LOCATION"CT23"
CDS_LMAN_SYM_OUTLINE"-50,25,50,-25"
CDS_LIB"w_hdl"
PART_NUMBER"78.22224.2BL"
PACK_TYPE"SMD-BCG6"
LOCATION"CT23"
VALUE"SC2K2P50V3KX-GP"
STATUS"NOPOP";
"2"
$PN"2"20;
"1"
$PN"1"37;
%"GND"
"1","(-2400,2850)","0","mstr_symbols","I78";
;
HDL_POWER"GND"
BODY_TYPE"PLUMBING"
ROOM"PVCCIN_CPU0_PWR_VR"
BOM_COST"PROC_VRD_VCCIN_CPU0"
VOLTAGE"0"
SIZE"1B"
CDS_LIB"mstr_symbols";
"A\NAC"16;
%"CAP_A"
"1","(-1425,3325)","0","dev_discrete","I8";
;
ROOM"PVCCIN_CPU1_PWR_VR"
SEC"1"
SEC_TYPE"0603V"
CDS_SEC"1"
BOM_COST"PROC_VRD_VCCIN_CPU0"
CDS_LOCATION"C9R8"
CDS_LIB"dev_discrete"
PACK_TYPE"0603V"
LOCATION"C9R8"
PART_NUMBER"E15431-004"
VALUE"22.0UF"
VOLTAGE"4V"
TOLERANCE"20%"
MATERIAL"X6S";
"B"
$PN"2"19;
"A"
$PN"1"12;
%"GND"
"1","(-4150,475)","0","mstr_symbols","I80";
;
HDL_POWER"GND"
BODY_TYPE"PLUMBING"
CDS_LIB"mstr_symbols"
VOLTAGE"0"
SIZE"1B"
BOM_COST"PROC_VRD_VCCIN_CPU0"
ROOM"PVCCIN_CPU0_PWR_VR";
"A\NAC"17;
%"CAP_A"
"1","(-4150,725)","0","dev_discrete","I81";
;
CDS_SEC"1"
$SEC"1"
CDS_LOCATION"CT25"
CDS_LIB"dev_discrete"
ROOM"PVCCIN_CPU0_PWR_VR"
VALUE"0.1UF"
VOLTAGE"16V"
TOLERANCE"10%"
MATERIAL"X7R"
PART_NUMBER"A36096-030"
PACK_TYPE"0402V"
LOCATION"CT25"
STATUS"NOPOP";
"B"
$PN"2"17;
"A"
$PN"1"22;
%"CAP"
"1","(-2400,1225)","0","mstr_discrete","I82";
;
CDS_SEC"1"
$SEC"1"
CDS_LOCATION"CT26"
CDS_LIB"mstr_discrete"
ROOM"VDDQ_KLM_PWR_VR"
PACK_TYPE"0402LF"
VOLTAGE"50V"
VALUE"1000PF"
MATERIAL"X7R"
STATUS"NOPOP"
TOLERANCE"10%"
LOCATION"CT26"
PART_NUMBER"A36096-046";
"A"
$PN"1"26;
"B"
$PN"2"18;
%"GND"
"1","(-2400,1025)","0","mstr_symbols","I83";
;
HDL_POWER"GND"
BODY_TYPE"PLUMBING"
CDS_LIB"mstr_symbols"
ROOM"VDDQ_KLM_PWR_VR"
VOLTAGE"0"
SIZE"1B";
"A\NAC"18;
%"SC2K2P50V3KX-GP"
"1","(-2350,825)","0","w_hdl","I84";
;
CDS_SEC"1"
$SEC"1"
CDS_LOCATION"CT27"
CDS_LMAN_SYM_OUTLINE"-50,25,50,-25"
CDS_LIB"w_hdl"
PART_NUMBER"78.22224.2BL"
PACK_TYPE"SMD-BCG6"
STATUS"NOPOP"
LOCATION"CT27"
VALUE"SC2K2P50V3KX-GP";
"2"
$PN"2"21;
"1"
$PN"1"24;
%"3D01R5F-GP"
"1","(-2350,550)","4","w_hdl","I85";
;
CDS_SEC"1"
$SEC"1"
CDS_LOCATION"RT18"
PACK_TYPE"SMD-RG5"
PART_NUMBER"64.3R015.16L"
CDS_LIB"w_hdl"
CDS_LMAN_SYM_OUTLINE"-50,75,50,-75"
LOCATION"RT18"
STATUS"NOPOP"
VALUE"3D01R5F-GP";
"2"
$PN"2"21;
"1"
$PN"1"48;
%"GND"
"1","(-2350,375)","0","mstr_symbols","I86";
;
HDL_POWER"GND"
BODY_TYPE"PLUMBING"
CDS_LIB"mstr_symbols"
SIZE"1B"
VOLTAGE"0"
BOM_COST"PROC_VRD_VCCIN_CPU0"
ROOM"PVCCIN_CPU0_PWR_VR";
"A\NAC"48;
%"RES"
"1","(-5150,3650)","0","mstr_discrete","I87";
;
CDS_SEC"1"
$SEC"1"
CDS_LOCATION"RT15"
ROOM"BMC_DEBUG_HEADER"
BOM_COST"DEBUG"
CDS_LIB"mstr_discrete"
PART_NUMBER"G21497-005"
PACK_TYPE"0402"
MATERIAL"CHIP"
TOLERANCE"5%"
VALUE"0.0"
WATTAGE"1/16W"
LOCATION"RT15";
"B"
$PN"2"38;
"A"
$PN"1"32;
%"RES"
"1","(-5025,1000)","0","mstr_discrete","I88";
;
CDS_SEC"1"
$SEC"1"
CDS_LOCATION"RT17"
BOM_COST"DEBUG"
ROOM"BMC_DEBUG_HEADER"
CDS_LIB"mstr_discrete"
LOCATION"RT17"
MATERIAL"CHIP"
TOLERANCE"5%"
PART_NUMBER"G21497-005"
VALUE"0.0"
WATTAGE"1/16W"
PACK_TYPE"0402";
"B"
$PN"2"30;
"A"
$PN"1"28;
%"GND"
"1","(-1425,3100)","0","mstr_symbols","I9";
;
HDL_POWER"GND"
BODY_TYPE"PLUMBING"
VOLTAGE"0"
CDS_LIB"mstr_symbols"
BOM_COST"PROC_VRD_VCCIN_CPU0"
ROOM"PVCCIN_CPU1_PWR_VR"
SIZE"1B";
"A\NAC"19;
END.
